(kicad_pcb
	(version 20260206)
	(generator "pcbnew")
	(generator_version "10.0")
	(general
		(thickness 1.6)
		(legacy_teardrops no)
	)
	(paper "A4")
	(title_block
		(title "baseboard — 13948-1b.1110WZS1818.brd")
		(comment 1 "Honey Badger (Wiwynn) / footprints 2501-2508 of 2523")
	)
	(layers
		(0 "F.Cu" signal "TOP")
		(4 "In1.Cu" signal "L2GND")
		(6 "In2.Cu" signal "L3")
		(8 "In3.Cu" signal "L4VCC")
		(10 "In4.Cu" signal "L5VCC")
		(12 "In5.Cu" signal "L6")
		(14 "In6.Cu" signal "L7GND")
		(2 "B.Cu" signal "BOTTOM")
		(9 "F.Adhes" user "F.Adhesive")
		(11 "B.Adhes" user "B.Adhesive")
		(13 "F.Paste" user "Package Geometry/Pastemask Top")
		(15 "B.Paste" user "Package Geometry/Pastemask Bottom")
		(5 "F.SilkS" user "Ref Des/Silkscreen Top")
		(7 "B.SilkS" user "Ref Des/Silkscreen Bottom")
		(1 "F.Mask" user "Board Geometry/Soldermask Top")
		(3 "B.Mask" user "Board Geometry/Soldermask Bottom")
		(17 "Dwgs.User" user "User.Drawings")
		(19 "Cmts.User" user "User.Comments")
		(21 "Eco1.User" user "User.Eco1")
		(23 "Eco2.User" user "User.Eco2")
		(25 "Edge.Cuts" user "Board Geometry/Outline")
		(27 "Margin" user)
		(31 "F.CrtYd" user "Package Geometry/Place Bound Top")
		(29 "B.CrtYd" user "Package Geometry/Place Bound Bottom")
		(35 "F.Fab" user "Ref Des/Assembly Top")
		(33 "B.Fab" user "Ref Des/Assembly Bottom")
	)
	(footprint ""
		(layer "B.Cu")
		(at 107.169966 -48.26 90)
		(property "Reference" "SC1053"
			(at 0 0 90)
			(layer "B.SilkS")
			(hide yes)
			(effects
				(font
					(size 1.27 1.27)
				)
				(justify mirror)
			)
		)
		(property "Value" "SCD1U16V2KX-3GP"
			(at -1.1811 -2.7051 90)
			(unlocked yes)
			(layer "B.Fab")
			(hide yes)
			(effects
				(font
					(size 1.016 1.016)
					(thickness 0.1524)
				)
				(justify mirror)
			)
		)
		(property "Device Type" "C402H22"
			(at -1.1811 -4.2291 90)
			(unlocked yes)
			(layer "B.Fab")
			(hide yes)
			(effects
				(font
					(size 1.016 1.016)
					(thickness 0.1524)
				)
				(justify mirror)
			)
		)
		(duplicate_pad_numbers_are_jumpers no)
		(fp_rect
			(start 0.4318 0.9525)
			(end -0.4318 -0.9525)
			(stroke
				(width 0)
				(type default)
			)
			(fill no)
			(layer "B.CrtYd")
		)
		(fp_rect
			(start 0.4318 0.9525)
			(end -0.4318 -0.9525)
			(stroke
				(width 0)
				(type default)
			)
			(fill no)
			(layer "B.Fab")
		)
		(pad "1" smd custom
			(at 0 -0.4445 270)
			(size 0.1524 0.1524)
			(layers "B.Cu" "B.Mask" "B.Paste")
			(net "P0V955_C")
			(options
				(clearance outline)
				(anchor circle)
			)
			(primitives
				(gr_poly
					(pts
						(arc
							(start 0.3048 0.2032)
							(mid 0.275042 0.275042)
							(end 0.2032 0.3048)
						)
						(arc
							(start -0.2032 0.3048)
							(mid -0.275042 0.275042)
							(end -0.3048 0.2032)
						)
						(arc
							(start -0.3048 -0.2032)
							(mid -0.275042 -0.275042)
							(end -0.2032 -0.3048)
						)
						(arc
							(start 0.2032 -0.3048)
							(mid 0.275042 -0.275042)
							(end 0.3048 -0.2032)
						)
					)
					(width 0)
					(fill yes)
				)
			)
		)
		(pad "2" smd custom
			(at 0 0.4445 270)
			(size 0.1524 0.1524)
			(layers "B.Cu" "B.Mask" "B.Paste")
			(net "GND")
			(options
				(clearance outline)
				(anchor circle)
			)
			(primitives
				(gr_poly
					(pts
						(arc
							(start 0.3048 0.2032)
							(mid 0.275042 0.275042)
							(end 0.2032 0.3048)
						)
						(arc
							(start -0.2032 0.3048)
							(mid -0.275042 0.275042)
							(end -0.3048 0.2032)
						)
						(arc
							(start -0.3048 -0.2032)
							(mid -0.275042 -0.275042)
							(end -0.2032 -0.3048)
						)
						(arc
							(start 0.2032 -0.3048)
							(mid 0.275042 -0.275042)
							(end 0.3048 -0.2032)
						)
					)
					(width 0)
					(fill yes)
				)
			)
		)
	)
	(footprint ""
		(layer "B.Cu")
		(at 112.532668 -35.32251)
		(property "Reference" "STP2"
			(at 0 0 0)
			(layer "B.SilkS")
			(hide yes)
			(effects
				(font
					(size 1.27 1.27)
				)
				(justify mirror)
			)
		)
		(property "Value" "TPAD28"
			(at -0.0127 -1.8034 0)
			(unlocked yes)
			(layer "B.Fab")
			(hide yes)
			(effects
				(font
					(size 1.016 1.016)
					(thickness 0.1524)
				)
				(justify mirror)
			)
		)
		(property "Device Type" "TPAD28"
			(at -0.0127 -3.3274 0)
			(unlocked yes)
			(layer "B.Fab")
			(hide yes)
			(effects
				(font
					(size 1.016 1.016)
					(thickness 0.1524)
				)
				(justify mirror)
			)
		)
		(duplicate_pad_numbers_are_jumpers no)
		(fp_poly
			(pts
				(arc
					(start 0.3556 0)
					(mid -0.3556 0)
					(end 0.3556 0)
				)
			)
			(stroke
				(width 0)
				(type default)
			)
			(fill no)
			(layer "B.CrtYd")
		)
		(fp_poly
			(pts
				(arc
					(start 0.6096 0)
					(mid -0.6096 0)
					(end 0.6096 0)
				)
			)
			(stroke
				(width 0)
				(type default)
			)
			(fill no)
			(layer "B.Fab")
		)
		(pad "1" smd circle
			(at 0 0 180)
			(size 0.7112 0.7112)
			(layers "B.Cu" "B.Mask" "B.Paste")
			(net "IOC_GPIO_25")
		)
	)
	(footprint ""
		(layer "B.Cu")
		(at 96.40316 -31.623)
		(property "Reference" "SC865"
			(at 0 0 0)
			(layer "B.SilkS")
			(hide yes)
			(effects
				(font
					(size 1.27 1.27)
				)
				(justify mirror)
			)
		)
		(property "Value" "SCD22U6D3V1MX-1-GP"
			(at 2.8321 -1.7399 0)
			(unlocked yes)
			(layer "B.Fab")
			(hide yes)
			(effects
				(font
					(size 1.016 1.016)
					(thickness 0.1524)
				)
				(justify mirror)
			)
		)
		(property "Device Type" "C0201H13"
			(at 2.8321 -3.2639 0)
			(unlocked yes)
			(layer "B.Fab")
			(hide yes)
			(effects
				(font
					(size 1.016 1.016)
					(thickness 0.1524)
				)
				(justify mirror)
			)
		)
		(duplicate_pad_numbers_are_jumpers no)
		(fp_rect
			(start 0.2794 0.6477)
			(end -0.2794 -0.6477)
			(stroke
				(width 0)
				(type default)
			)
			(fill no)
			(layer "B.CrtYd")
		)
		(fp_rect
			(start 0.2794 0.6477)
			(end -0.2794 -0.6477)
			(stroke
				(width 0)
				(type default)
			)
			(fill no)
			(layer "B.Fab")
		)
		(pad "1" smd custom
			(at 0 -0.2794 180)
			(size 0.0762 0.0762)
			(layers "B.Cu" "B.Mask" "B.Paste")
			(net "PCIE_SAS_C_CPU_RX_P2")
			(options
				(clearance outline)
				(anchor circle)
			)
			(primitives
				(gr_poly
					(pts
						(arc
							(start 0.1524 0.127)
							(mid 0.137521 0.162921)
							(end 0.1016 0.1778)
						)
						(arc
							(start -0.1016 0.1778)
							(mid -0.137521 0.162921)
							(end -0.1524 0.127)
						)
						(arc
							(start -0.1524 -0.127)
							(mid -0.137521 -0.162921)
							(end -0.1016 -0.1778)
						)
						(arc
							(start 0.1016 -0.1778)
							(mid 0.137521 -0.162921)
							(end 0.1524 -0.127)
						)
					)
					(width 0)
					(fill yes)
				)
			)
		)
		(pad "2" smd custom
			(at 0 0.2794 180)
			(size 0.0762 0.0762)
			(layers "B.Cu" "B.Mask" "B.Paste")
			(net "PCIE_SAS_CPU_RX_P2")
			(options
				(clearance outline)
				(anchor circle)
			)
			(primitives
				(gr_poly
					(pts
						(arc
							(start 0.1524 0.127)
							(mid 0.137521 0.162921)
							(end 0.1016 0.1778)
						)
						(arc
							(start -0.1016 0.1778)
							(mid -0.137521 0.162921)
							(end -0.1524 0.127)
						)
						(arc
							(start -0.1524 -0.127)
							(mid -0.137521 -0.162921)
							(end -0.1016 -0.1778)
						)
						(arc
							(start 0.1016 -0.1778)
							(mid 0.137521 -0.162921)
							(end 0.1524 -0.127)
						)
					)
					(width 0)
					(fill yes)
				)
			)
		)
	)
	(footprint ""
		(layer "B.Cu")
		(at 117.037612 -222.885 180)
		(property "Reference" "SR891"
			(at 0 0 0)
			(layer "B.SilkS")
			(hide yes)
			(effects
				(font
					(size 1.27 1.27)
				)
				(justify mirror)
			)
		)
		(property "Value" "0R2J-2-GP"
			(at -0.064008 -3.993896 180)
			(unlocked yes)
			(layer "B.Fab")
			(hide yes)
			(effects
				(font
					(size 1.016 1.016)
					(thickness 0.1524)
				)
				(justify mirror)
			)
		)
		(property "Device Type" "R402H16"
			(at -0.064008 -5.517896 180)
			(unlocked yes)
			(layer "B.Fab")
			(hide yes)
			(effects
				(font
					(size 1.016 1.016)
					(thickness 0.1524)
				)
				(justify mirror)
			)
		)
		(duplicate_pad_numbers_are_jumpers no)
		(fp_line
			(start 0.508 -0.9398)
			(end 0.508 0.9398)
			(stroke
				(width 0.1524)
				(type default)
			)
			(layer "B.SilkS")
		)
		(fp_line
			(start -0.508 -0.9398)
			(end 0.508 -0.9398)
			(stroke
				(width 0.1524)
				(type default)
			)
			(layer "B.SilkS")
		)
		(fp_rect
			(start 0.508 0.9398)
			(end -0.508 -0.9398)
			(stroke
				(width 0)
				(type default)
			)
			(fill no)
			(layer "B.CrtYd")
		)
		(fp_rect
			(start 0.508 0.9398)
			(end -0.508 -0.9398)
			(stroke
				(width 0)
				(type default)
			)
			(fill no)
			(layer "B.Fab")
		)
		(pad "1" smd custom
			(at 0 -0.4445)
			(size 0.1397 0.1397)
			(layers "B.Cu" "B.Mask" "B.Paste")
			(net "SAS_GF_EXP_RX_DN7")
			(options
				(clearance outline)
				(anchor circle)
			)
			(primitives
				(gr_poly
					(pts
						(arc
							(start -0.1778 0.2794)
							(mid -0.249642 0.249642)
							(end -0.2794 0.1778)
						)
						(arc
							(start -0.2794 -0.1778)
							(mid -0.249642 -0.249642)
							(end -0.1778 -0.2794)
						)
						(arc
							(start 0.1778 -0.2794)
							(mid 0.249642 -0.249642)
							(end 0.2794 -0.1778)
						)
						(arc
							(start 0.2794 0.1778)
							(mid 0.249642 0.249642)
							(end 0.1778 0.2794)
						)
					)
					(width 0)
					(fill yes)
				)
			)
		)
		(pad "2" smd custom
			(at 0 0.4445)
			(size 0.1397 0.1397)
			(layers "B.Cu" "B.Mask" "B.Paste")
			(net "REDV_RX7_N")
			(options
				(clearance outline)
				(anchor circle)
			)
			(primitives
				(gr_poly
					(pts
						(arc
							(start -0.1778 0.2794)
							(mid -0.249642 0.249642)
							(end -0.2794 0.1778)
						)
						(arc
							(start -0.2794 -0.1778)
							(mid -0.249642 -0.249642)
							(end -0.1778 -0.2794)
						)
						(arc
							(start 0.1778 -0.2794)
							(mid 0.249642 -0.249642)
							(end 0.2794 -0.1778)
						)
						(arc
							(start 0.2794 0.1778)
							(mid 0.249642 0.249642)
							(end 0.1778 0.2794)
						)
					)
					(width 0)
					(fill yes)
				)
			)
		)
	)
	(footprint ""
		(layer "B.Cu")
		(at 325.374 -182.372 180)
		(property "Reference" "R3029"
			(at 0 0 0)
			(layer "B.SilkS")
			(hide yes)
			(effects
				(font
					(size 1.27 1.27)
				)
				(justify mirror)
			)
		)
		(property "Value" "1KR2F-3-GP"
			(at -0.064008 -3.993896 180)
			(unlocked yes)
			(layer "B.Fab")
			(hide yes)
			(effects
				(font
					(size 1.016 1.016)
					(thickness 0.1524)
				)
				(justify mirror)
			)
		)
		(property "Device Type" "R402H16"
			(at -0.064008 -5.517896 180)
			(unlocked yes)
			(layer "B.Fab")
			(hide yes)
			(effects
				(font
					(size 1.016 1.016)
					(thickness 0.1524)
				)
				(justify mirror)
			)
		)
		(duplicate_pad_numbers_are_jumpers no)
		(fp_line
			(start 0.508 -0.9398)
			(end 0.508 0.9398)
			(stroke
				(width 0.1524)
				(type default)
			)
			(layer "B.SilkS")
		)
		(fp_line
			(start -0.508 -0.9398)
			(end 0.508 -0.9398)
			(stroke
				(width 0.1524)
				(type default)
			)
			(layer "B.SilkS")
		)
		(fp_rect
			(start 0.508 0.9398)
			(end -0.508 -0.9398)
			(stroke
				(width 0)
				(type default)
			)
			(fill no)
			(layer "B.CrtYd")
		)
		(fp_rect
			(start 0.508 0.9398)
			(end -0.508 -0.9398)
			(stroke
				(width 0)
				(type default)
			)
			(fill no)
			(layer "B.Fab")
		)
		(pad "1" smd custom
			(at 0 -0.4445)
			(size 0.1397 0.1397)
			(layers "B.Cu" "B.Mask" "B.Paste")
			(net "P0V955_C")
			(options
				(clearance outline)
				(anchor circle)
			)
			(primitives
				(gr_poly
					(pts
						(arc
							(start -0.1778 0.2794)
							(mid -0.249642 0.249642)
							(end -0.2794 0.1778)
						)
						(arc
							(start -0.2794 -0.1778)
							(mid -0.249642 -0.249642)
							(end -0.1778 -0.2794)
						)
						(arc
							(start 0.1778 -0.2794)
							(mid 0.249642 -0.249642)
							(end 0.2794 -0.1778)
						)
						(arc
							(start 0.2794 0.1778)
							(mid 0.249642 0.249642)
							(end 0.1778 0.2794)
						)
					)
					(width 0)
					(fill yes)
				)
			)
		)
		(pad "2" smd custom
			(at 0 0.4445)
			(size 0.1397 0.1397)
			(layers "B.Cu" "B.Mask" "B.Paste")
			(net "ADC_P0V955_C")
			(options
				(clearance outline)
				(anchor circle)
			)
			(primitives
				(gr_poly
					(pts
						(arc
							(start -0.1778 0.2794)
							(mid -0.249642 0.249642)
							(end -0.2794 0.1778)
						)
						(arc
							(start -0.2794 -0.1778)
							(mid -0.249642 -0.249642)
							(end -0.1778 -0.2794)
						)
						(arc
							(start 0.1778 -0.2794)
							(mid 0.249642 -0.249642)
							(end 0.2794 -0.1778)
						)
						(arc
							(start 0.2794 0.1778)
							(mid 0.249642 0.249642)
							(end 0.1778 0.2794)
						)
					)
					(width 0)
					(fill yes)
				)
			)
		)
	)
	(footprint ""
		(layer "B.Cu")
		(at 108.020612 -209.423 -90)
		(property "Reference" "SC1289"
			(at 0 0 90)
			(layer "B.SilkS")
			(hide yes)
			(effects
				(font
					(size 1.27 1.27)
				)
				(justify mirror)
			)
		)
		(property "Value" "SC1U10V2KX-4-GP"
			(at -1.1811 -2.7051 270)
			(unlocked yes)
			(layer "B.Fab")
			(hide yes)
			(effects
				(font
					(size 1.016 1.016)
					(thickness 0.1524)
				)
				(justify mirror)
			)
		)
		(property "Device Type" "C402H22"
			(at -1.1811 -4.2291 270)
			(unlocked yes)
			(layer "B.Fab")
			(hide yes)
			(effects
				(font
					(size 1.016 1.016)
					(thickness 0.1524)
				)
				(justify mirror)
			)
		)
		(duplicate_pad_numbers_are_jumpers no)
		(fp_rect
			(start 0.4318 0.9525)
			(end -0.4318 -0.9525)
			(stroke
				(width 0)
				(type default)
			)
			(fill no)
			(layer "B.CrtYd")
		)
		(fp_rect
			(start 0.4318 0.9525)
			(end -0.4318 -0.9525)
			(stroke
				(width 0)
				(type default)
			)
			(fill no)
			(layer "B.Fab")
		)
		(pad "1" smd custom
			(at 0 -0.4445 90)
			(size 0.1524 0.1524)
			(layers "B.Cu" "B.Mask" "B.Paste")
			(net "1.2V_REDV")
			(options
				(clearance outline)
				(anchor circle)
			)
			(primitives
				(gr_poly
					(pts
						(arc
							(start 0.3048 0.2032)
							(mid 0.275042 0.275042)
							(end 0.2032 0.3048)
						)
						(arc
							(start -0.2032 0.3048)
							(mid -0.275042 0.275042)
							(end -0.3048 0.2032)
						)
						(arc
							(start -0.3048 -0.2032)
							(mid -0.275042 -0.275042)
							(end -0.2032 -0.3048)
						)
						(arc
							(start 0.2032 -0.3048)
							(mid 0.275042 -0.275042)
							(end 0.3048 -0.2032)
						)
					)
					(width 0)
					(fill yes)
				)
			)
		)
		(pad "2" smd custom
			(at 0 0.4445 90)
			(size 0.1524 0.1524)
			(layers "B.Cu" "B.Mask" "B.Paste")
			(net "GND")
			(options
				(clearance outline)
				(anchor circle)
			)
			(primitives
				(gr_poly
					(pts
						(arc
							(start 0.3048 0.2032)
							(mid 0.275042 0.275042)
							(end 0.2032 0.3048)
						)
						(arc
							(start -0.2032 0.3048)
							(mid -0.275042 0.275042)
							(end -0.3048 0.2032)
						)
						(arc
							(start -0.3048 -0.2032)
							(mid -0.275042 -0.275042)
							(end -0.2032 -0.3048)
						)
						(arc
							(start 0.2032 -0.3048)
							(mid 0.275042 -0.275042)
							(end 0.3048 -0.2032)
						)
					)
					(width 0)
					(fill yes)
				)
			)
		)
	)
	(footprint ""
		(layer "B.Cu")
		(at 11.938 -221.615 90)
		(property "Reference" "SR315"
			(at 0 0 90)
			(layer "B.SilkS")
			(hide yes)
			(effects
				(font
					(size 1.27 1.27)
				)
				(justify mirror)
			)
		)
		(property "Value" "0R2J-2-GP"
			(at -0.064008 -3.993896 90)
			(unlocked yes)
			(layer "B.Fab")
			(hide yes)
			(effects
				(font
					(size 1.016 1.016)
					(thickness 0.1524)
				)
				(justify mirror)
			)
		)
		(property "Device Type" "R402H16"
			(at -0.064008 -5.517896 90)
			(unlocked yes)
			(layer "B.Fab")
			(hide yes)
			(effects
				(font
					(size 1.016 1.016)
					(thickness 0.1524)
				)
				(justify mirror)
			)
		)
		(duplicate_pad_numbers_are_jumpers no)
		(fp_line
			(start 0.508 -0.9398)
			(end 0.508 0.9398)
			(stroke
				(width 0.1524)
				(type default)
			)
			(layer "B.SilkS")
		)
		(fp_line
			(start -0.508 -0.9398)
			(end 0.508 -0.9398)
			(stroke
				(width 0.1524)
				(type default)
			)
			(layer "B.SilkS")
		)
		(fp_rect
			(start 0.508 0.9398)
			(end -0.508 -0.9398)
			(stroke
				(width 0)
				(type default)
			)
			(fill no)
			(layer "B.CrtYd")
		)
		(fp_rect
			(start 0.508 0.9398)
			(end -0.508 -0.9398)
			(stroke
				(width 0)
				(type default)
			)
			(fill no)
			(layer "B.Fab")
		)
		(pad "1" smd custom
			(at 0 -0.4445 270)
			(size 0.1397 0.1397)
			(layers "B.Cu" "B.Mask" "B.Paste")
			(net "EXP_SCL_0")
			(options
				(clearance outline)
				(anchor circle)
			)
			(primitives
				(gr_poly
					(pts
						(arc
							(start -0.1778 0.2794)
							(mid -0.249642 0.249642)
							(end -0.2794 0.1778)
						)
						(arc
							(start -0.2794 -0.1778)
							(mid -0.249642 -0.249642)
							(end -0.1778 -0.2794)
						)
						(arc
							(start 0.1778 -0.2794)
							(mid 0.249642 -0.249642)
							(end 0.2794 -0.1778)
						)
						(arc
							(start 0.2794 0.1778)
							(mid 0.249642 0.249642)
							(end 0.1778 0.2794)
						)
					)
					(width 0)
					(fill yes)
				)
			)
		)
		(pad "2" smd custom
			(at 0 0.4445 270)
			(size 0.1397 0.1397)
			(layers "B.Cu" "B.Mask" "B.Paste")
			(net "BMC_IOEXP_SCL_10")
			(options
				(clearance outline)
				(anchor circle)
			)
			(primitives
				(gr_poly
					(pts
						(arc
							(start -0.1778 0.2794)
							(mid -0.249642 0.249642)
							(end -0.2794 0.1778)
						)
						(arc
							(start -0.2794 -0.1778)
							(mid -0.249642 -0.249642)
							(end -0.1778 -0.2794)
						)
						(arc
							(start 0.1778 -0.2794)
							(mid 0.249642 -0.249642)
							(end 0.2794 -0.1778)
						)
						(arc
							(start 0.2794 0.1778)
							(mid 0.249642 0.249642)
							(end 0.1778 0.2794)
						)
					)
					(width 0)
					(fill yes)
				)
			)
		)
	)
	(footprint ""
		(layer "B.Cu")
		(at 45.54093 -77.650086)
		(property "Reference" "SC1277"
			(at 0 0 0)
			(layer "B.SilkS")
			(hide yes)
			(effects
				(font
					(size 1.27 1.27)
				)
				(justify mirror)
			)
		)
		(property "Value" "SCD01U50V2KX-1GP"
			(at -1.1811 -2.7051 0)
			(unlocked yes)
			(layer "B.Fab")
			(hide yes)
			(effects
				(font
					(size 1.016 1.016)
					(thickness 0.1524)
				)
				(justify mirror)
			)
		)
		(property "Device Type" "C402H22"
			(at -1.1811 -4.2291 0)
			(unlocked yes)
			(layer "B.Fab")
			(hide yes)
			(effects
				(font
					(size 1.016 1.016)
					(thickness 0.1524)
				)
				(justify mirror)
			)
		)
		(duplicate_pad_numbers_are_jumpers no)
		(fp_rect
			(start 0.4318 0.9525)
			(end -0.4318 -0.9525)
			(stroke
				(width 0)
				(type default)
			)
			(fill no)
			(layer "B.CrtYd")
		)
		(fp_rect
			(start 0.4318 0.9525)
			(end -0.4318 -0.9525)
			(stroke
				(width 0)
				(type default)
			)
			(fill no)
			(layer "B.Fab")
		)
		(pad "1" smd custom
			(at 0 -0.4445 180)
			(size 0.1524 0.1524)
			(layers "B.Cu" "B.Mask" "B.Paste")
			(net "SAS_EXP2CONN_RX_N_21")
			(options
				(clearance outline)
				(anchor circle)
			)
			(primitives
				(gr_poly
					(pts
						(arc
							(start 0.3048 0.2032)
							(mid 0.275042 0.275042)
							(end 0.2032 0.3048)
						)
						(arc
							(start -0.2032 0.3048)
							(mid -0.275042 0.275042)
							(end -0.3048 0.2032)
						)
						(arc
							(start -0.3048 -0.2032)
							(mid -0.275042 -0.275042)
							(end -0.2032 -0.3048)
						)
						(arc
							(start 0.2032 -0.3048)
							(mid 0.275042 -0.275042)
							(end 0.3048 -0.2032)
						)
					)
					(width 0)
					(fill yes)
				)
			)
		)
		(pad "2" smd custom
			(at 0 0.4445 180)
			(size 0.1524 0.1524)
			(layers "B.Cu" "B.Mask" "B.Paste")
			(net "MINI_RX_N_21")
			(options
				(clearance outline)
				(anchor circle)
			)
			(primitives
				(gr_poly
					(pts
						(arc
							(start 0.3048 0.2032)
							(mid 0.275042 0.275042)
							(end 0.2032 0.3048)
						)
						(arc
							(start -0.2032 0.3048)
							(mid -0.275042 0.275042)
							(end -0.3048 0.2032)
						)
						(arc
							(start -0.3048 -0.2032)
							(mid -0.275042 -0.275042)
							(end -0.2032 -0.3048)
						)
						(arc
							(start 0.2032 -0.3048)
							(mid 0.275042 -0.275042)
							(end 0.3048 -0.2032)
						)
					)
					(width 0)
					(fill yes)
				)
			)
		)
	)
)
